(kicad_pcb
	(version 20260206)
	(generator "pcbnew")
	(generator_version "10.0")
	(general
		(thickness 1.6)
		(legacy_teardrops no)
	)
	(paper "A4")
	(title_block
		(title "12092022_DA0F0TMDCD0_F0T_Management_Board_D_brd_V3_OCP.brd")
		(comment 1 "Grand Teton / footprints 97-103 of 1440")
	)
	(layers
		(0 "F.Cu" signal "TOP")
		(4 "In1.Cu" signal "GND")
		(6 "In2.Cu" signal "IN1")
		(8 "In3.Cu" signal "GND1")
		(10 "In4.Cu" signal "IN2")
		(12 "In5.Cu" signal "VCC")
		(14 "In6.Cu" signal "VCC1")
		(16 "In7.Cu" signal "IN3")
		(18 "In8.Cu" signal "GND2")
		(20 "In9.Cu" signal "IN4")
		(22 "In10.Cu" signal "GND3")
		(2 "B.Cu" signal "BOTTOM")
		(9 "F.Adhes" user "F.Adhesive")
		(11 "B.Adhes" user "B.Adhesive")
		(13 "F.Paste" user "Package Geometry/Pastemask Top")
		(15 "B.Paste" user "Package Geometry/Pastemask Bottom")
		(5 "F.SilkS" user "Ref Des/Silkscreen Top")
		(7 "B.SilkS" user "Ref Des/Silkscreen Bottom")
		(1 "F.Mask" user "Board Geometry/Soldermask Top")
		(3 "B.Mask" user "Board Geometry/Soldermask Bottom")
		(17 "Dwgs.User" user "User.Drawings")
		(19 "Cmts.User" user "User.Comments")
		(21 "Eco1.User" user "User.Eco1")
		(23 "Eco2.User" user "User.Eco2")
		(25 "Edge.Cuts" user "Board Geometry/Outline")
		(27 "Margin" user)
		(31 "F.CrtYd" user "Package Geometry/Place Bound Top")
		(29 "B.CrtYd" user "Package Geometry/Place Bound Bottom")
		(35 "F.Fab" user "Ref Des/Assembly Top")
		(33 "B.Fab" user "Ref Des/Assembly Bottom")
	)
	(footprint ""
		(layer "F.Cu")
		(at 13.262864 -9.779 180)
		(property "Reference" "C191"
			(at 0 0 180)
			(layer "F.SilkS")
			(hide yes)
			(effects
				(font
					(size 1.27 1.27)
				)
			)
		)
		(property "Value" ""
			(at 0 0 180)
			(layer "F.Fab")
			(effects
				(font
					(size 1.27 1.27)
				)
			)
		)
		(duplicate_pad_numbers_are_jumpers no)
		(fp_line
			(start 0.7874 0.4064)
			(end -0.7874 0.4064)
			(stroke
				(width 0.1524)
				(type default)
			)
			(layer "F.SilkS")
		)
		(fp_line
			(start 0.7874 -0.4064)
			(end 0.7874 0.4064)
			(stroke
				(width 0.1524)
				(type default)
			)
			(layer "F.SilkS")
		)
		(fp_line
			(start -0.7874 0.4064)
			(end -0.7874 -0.4064)
			(stroke
				(width 0.1524)
				(type default)
			)
			(layer "F.SilkS")
		)
		(fp_line
			(start -0.7874 -0.4064)
			(end 0.7874 -0.4064)
			(stroke
				(width 0.1524)
				(type default)
			)
			(layer "F.SilkS")
		)
		(fp_line
			(start 0.67945 0.3048)
			(end 0.120396 0.3048)
			(stroke
				(width 0.1)
				(type default)
			)
			(layer "F.Fab")
		)
		(fp_line
			(start 0.67945 -0.3048)
			(end 0.67945 0.3048)
			(stroke
				(width 0.1)
				(type default)
			)
			(layer "F.Fab")
		)
		(fp_line
			(start 0.12065 -0.2794)
			(end 0.12065 -0.3048)
			(stroke
				(width 0.1)
				(type default)
			)
			(layer "F.Fab")
		)
		(fp_line
			(start 0.12065 -0.3048)
			(end 0.67945 -0.3048)
			(stroke
				(width 0.1)
				(type default)
			)
			(layer "F.Fab")
		)
		(fp_line
			(start 0.120396 0.3048)
			(end 0.120396 0.2794)
			(stroke
				(width 0.1)
				(type default)
			)
			(layer "F.Fab")
		)
		(fp_line
			(start 0.120396 0.2794)
			(end -0.12065 0.2794)
			(stroke
				(width 0.1)
				(type default)
			)
			(layer "F.Fab")
		)
		(fp_line
			(start -0.12065 0.3048)
			(end -0.67945 0.3048)
			(stroke
				(width 0.1)
				(type default)
			)
			(layer "F.Fab")
		)
		(fp_line
			(start -0.12065 0.2794)
			(end -0.12065 0.3048)
			(stroke
				(width 0.1)
				(type default)
			)
			(layer "F.Fab")
		)
		(fp_line
			(start -0.12065 -0.2794)
			(end 0.12065 -0.2794)
			(stroke
				(width 0.1)
				(type default)
			)
			(layer "F.Fab")
		)
		(fp_line
			(start -0.12065 -0.305054)
			(end -0.12065 -0.2794)
			(stroke
				(width 0.1)
				(type default)
			)
			(layer "F.Fab")
		)
		(fp_line
			(start -0.67945 0.3048)
			(end -0.67945 -0.305054)
			(stroke
				(width 0.1)
				(type default)
			)
			(layer "F.Fab")
		)
		(fp_line
			(start -0.67945 -0.305054)
			(end -0.12065 -0.305054)
			(stroke
				(width 0.1)
				(type default)
			)
			(layer "F.Fab")
		)
		(pad "1" smd circle
			(at -0.40005 0 180)
			(size 0 0)
			(layers "F.Cu" "F.Mask" "F.Paste")
			(net "P3V3_AUX")
		)
		(pad "2" smd circle
			(at 0.40005 0 180)
			(size 0 0)
			(layers "F.Cu" "F.Mask" "F.Paste")
			(net "GND")
		)
	)
	(footprint ""
		(layer "F.Cu")
		(at 2.65938 -18.161)
		(property "Reference" ""
			(at 0 0 0)
			(layer "F.SilkS")
			(hide yes)
			(effects
				(font
					(size 1.27 1.27)
				)
			)
		)
		(property "Value" ""
			(at 0 0 0)
			(layer "F.Fab")
			(effects
				(font
					(size 1.27 1.27)
				)
			)
		)
		(duplicate_pad_numbers_are_jumpers no)
		(pad "1" smd circle
			(at 0 0)
			(size 0.9906 0.9906)
			(layers "F.Cu" "F.Mask" "F.Paste")
			(net "Net_596")
		)
		(zone
			(layer "F.Cu")
			(hatch none 0.5)
			(connect_pads
				(clearance 0)
			)
			(min_thickness 0.25)
			(keepout
				(tracks not_allowed)
				(vias allowed)
				(pads allowed)
				(copperpour not_allowed)
				(footprints allowed)
			)
			(placement
				(enabled no)
				(sheetname "")
			)
			(fill
				(thermal_gap 0.5)
				(thermal_bridge_width 0.5)
				(island_removal_mode 0)
			)
			(polygon
				(pts
					(arc
						(start 4.28498 -18.161)
						(mid 1.03378 -18.161)
						(end 4.28498 -18.161)
					)
				)
			)
		)
	)
	(footprint ""
		(layer "F.Cu")
		(at 5.334 -80.899 -90)
		(property "Reference" "R614"
			(at 0 0 270)
			(layer "F.SilkS")
			(hide yes)
			(effects
				(font
					(size 1.27 1.27)
				)
			)
		)
		(property "Value" ""
			(at 0 0 270)
			(layer "F.Fab")
			(effects
				(font
					(size 1.27 1.27)
				)
			)
		)
		(duplicate_pad_numbers_are_jumpers no)
		(fp_line
			(start -0.7874 0.4064)
			(end -0.7874 -0.4064)
			(stroke
				(width 0.1524)
				(type default)
			)
			(layer "F.SilkS")
		)
		(fp_line
			(start 0.7874 0.4064)
			(end -0.7874 0.4064)
			(stroke
				(width 0.1524)
				(type default)
			)
			(layer "F.SilkS")
		)
		(fp_line
			(start -0.7874 -0.4064)
			(end 0.7874 -0.4064)
			(stroke
				(width 0.1524)
				(type default)
			)
			(layer "F.SilkS")
		)
		(fp_line
			(start 0.7874 -0.4064)
			(end 0.7874 0.4064)
			(stroke
				(width 0.1524)
				(type default)
			)
			(layer "F.SilkS")
		)
		(fp_line
			(start -0.67945 0.3048)
			(end -0.67945 -0.305054)
			(stroke
				(width 0.1)
				(type default)
			)
			(layer "F.Fab")
		)
		(fp_line
			(start -0.12065 0.3048)
			(end -0.67945 0.3048)
			(stroke
				(width 0.1)
				(type default)
			)
			(layer "F.Fab")
		)
		(fp_line
			(start 0.120396 0.3048)
			(end 0.120396 0.2794)
			(stroke
				(width 0.1)
				(type default)
			)
			(layer "F.Fab")
		)
		(fp_line
			(start 0.67945 0.3048)
			(end 0.120396 0.3048)
			(stroke
				(width 0.1)
				(type default)
			)
			(layer "F.Fab")
		)
		(fp_line
			(start -0.12065 0.2794)
			(end -0.12065 0.3048)
			(stroke
				(width 0.1)
				(type default)
			)
			(layer "F.Fab")
		)
		(fp_line
			(start 0.120396 0.2794)
			(end -0.12065 0.2794)
			(stroke
				(width 0.1)
				(type default)
			)
			(layer "F.Fab")
		)
		(fp_line
			(start -0.12065 -0.2794)
			(end 0.12065 -0.2794)
			(stroke
				(width 0.1)
				(type default)
			)
			(layer "F.Fab")
		)
		(fp_line
			(start 0.12065 -0.2794)
			(end 0.12065 -0.3048)
			(stroke
				(width 0.1)
				(type default)
			)
			(layer "F.Fab")
		)
		(fp_line
			(start 0.12065 -0.3048)
			(end 0.67945 -0.3048)
			(stroke
				(width 0.1)
				(type default)
			)
			(layer "F.Fab")
		)
		(fp_line
			(start 0.67945 -0.3048)
			(end 0.67945 0.3048)
			(stroke
				(width 0.1)
				(type default)
			)
			(layer "F.Fab")
		)
		(fp_line
			(start -0.67945 -0.305054)
			(end -0.12065 -0.305054)
			(stroke
				(width 0.1)
				(type default)
			)
			(layer "F.Fab")
		)
		(fp_line
			(start -0.12065 -0.305054)
			(end -0.12065 -0.2794)
			(stroke
				(width 0.1)
				(type default)
			)
			(layer "F.Fab")
		)
		(pad "1" smd circle
			(at -0.40005 0 270)
			(size 0 0)
			(layers "F.Cu" "F.Mask" "F.Paste")
			(net "RST_SRST_PLD_BMC_R1_N")
		)
		(pad "2" smd circle
			(at 0.40005 0 270)
			(size 0 0)
			(layers "F.Cu" "F.Mask" "F.Paste")
			(net "GND")
		)
	)
	(footprint ""
		(layer "F.Cu")
		(at 45.062902 -63.756794 -90)
		(property "Reference" "R23"
			(at 0 0 270)
			(layer "F.SilkS")
			(hide yes)
			(effects
				(font
					(size 1.27 1.27)
				)
			)
		)
		(property "Value" ""
			(at 0 0 270)
			(layer "F.Fab")
			(effects
				(font
					(size 1.27 1.27)
				)
			)
		)
		(duplicate_pad_numbers_are_jumpers no)
		(fp_line
			(start -0.7874 0.4064)
			(end -0.7874 -0.4064)
			(stroke
				(width 0.1524)
				(type default)
			)
			(layer "F.SilkS")
		)
		(fp_line
			(start 0.7874 0.4064)
			(end -0.7874 0.4064)
			(stroke
				(width 0.1524)
				(type default)
			)
			(layer "F.SilkS")
		)
		(fp_line
			(start -0.7874 -0.4064)
			(end 0.7874 -0.4064)
			(stroke
				(width 0.1524)
				(type default)
			)
			(layer "F.SilkS")
		)
		(fp_line
			(start 0.7874 -0.4064)
			(end 0.7874 0.4064)
			(stroke
				(width 0.1524)
				(type default)
			)
			(layer "F.SilkS")
		)
		(fp_line
			(start -0.67945 0.3048)
			(end -0.67945 -0.305054)
			(stroke
				(width 0.1)
				(type default)
			)
			(layer "F.Fab")
		)
		(fp_line
			(start -0.12065 0.3048)
			(end -0.67945 0.3048)
			(stroke
				(width 0.1)
				(type default)
			)
			(layer "F.Fab")
		)
		(fp_line
			(start 0.120396 0.3048)
			(end 0.120396 0.2794)
			(stroke
				(width 0.1)
				(type default)
			)
			(layer "F.Fab")
		)
		(fp_line
			(start 0.67945 0.3048)
			(end 0.120396 0.3048)
			(stroke
				(width 0.1)
				(type default)
			)
			(layer "F.Fab")
		)
		(fp_line
			(start -0.12065 0.2794)
			(end -0.12065 0.3048)
			(stroke
				(width 0.1)
				(type default)
			)
			(layer "F.Fab")
		)
		(fp_line
			(start 0.120396 0.2794)
			(end -0.12065 0.2794)
			(stroke
				(width 0.1)
				(type default)
			)
			(layer "F.Fab")
		)
		(fp_line
			(start -0.12065 -0.2794)
			(end 0.12065 -0.2794)
			(stroke
				(width 0.1)
				(type default)
			)
			(layer "F.Fab")
		)
		(fp_line
			(start 0.12065 -0.2794)
			(end 0.12065 -0.3048)
			(stroke
				(width 0.1)
				(type default)
			)
			(layer "F.Fab")
		)
		(fp_line
			(start 0.12065 -0.3048)
			(end 0.67945 -0.3048)
			(stroke
				(width 0.1)
				(type default)
			)
			(layer "F.Fab")
		)
		(fp_line
			(start 0.67945 -0.3048)
			(end 0.67945 0.3048)
			(stroke
				(width 0.1)
				(type default)
			)
			(layer "F.Fab")
		)
		(fp_line
			(start -0.67945 -0.305054)
			(end -0.12065 -0.305054)
			(stroke
				(width 0.1)
				(type default)
			)
			(layer "F.Fab")
		)
		(fp_line
			(start -0.12065 -0.305054)
			(end -0.12065 -0.2794)
			(stroke
				(width 0.1)
				(type default)
			)
			(layer "F.Fab")
		)
		(pad "1" smd circle
			(at -0.40005 0 270)
			(size 0 0)
			(layers "F.Cu" "F.Mask" "F.Paste")
			(net "V_DACG_R")
		)
		(pad "2" smd circle
			(at 0.40005 0 270)
			(size 0 0)
			(layers "F.Cu" "F.Mask" "F.Paste")
			(net "GND")
		)
	)
	(footprint ""
		(layer "F.Cu")
		(at 35.941 -60.96 90)
		(property "Reference" "R65"
			(at 0 0 90)
			(layer "F.SilkS")
			(hide yes)
			(effects
				(font
					(size 1.27 1.27)
				)
			)
		)
		(property "Value" ""
			(at 0 0 90)
			(layer "F.Fab")
			(effects
				(font
					(size 1.27 1.27)
				)
			)
		)
		(duplicate_pad_numbers_are_jumpers no)
		(fp_line
			(start 0.7874 -0.4064)
			(end 0.7874 0.4064)
			(stroke
				(width 0.1524)
				(type default)
			)
			(layer "F.SilkS")
		)
		(fp_line
			(start -0.7874 -0.4064)
			(end 0.7874 -0.4064)
			(stroke
				(width 0.1524)
				(type default)
			)
			(layer "F.SilkS")
		)
		(fp_line
			(start 0.7874 0.4064)
			(end -0.7874 0.4064)
			(stroke
				(width 0.1524)
				(type default)
			)
			(layer "F.SilkS")
		)
		(fp_line
			(start -0.7874 0.4064)
			(end -0.7874 -0.4064)
			(stroke
				(width 0.1524)
				(type default)
			)
			(layer "F.SilkS")
		)
		(fp_line
			(start -0.12065 -0.305054)
			(end -0.12065 -0.2794)
			(stroke
				(width 0.1)
				(type default)
			)
			(layer "F.Fab")
		)
		(fp_line
			(start -0.67945 -0.305054)
			(end -0.12065 -0.305054)
			(stroke
				(width 0.1)
				(type default)
			)
			(layer "F.Fab")
		)
		(fp_line
			(start 0.67945 -0.3048)
			(end 0.67945 0.3048)
			(stroke
				(width 0.1)
				(type default)
			)
			(layer "F.Fab")
		)
		(fp_line
			(start 0.12065 -0.3048)
			(end 0.67945 -0.3048)
			(stroke
				(width 0.1)
				(type default)
			)
			(layer "F.Fab")
		)
		(fp_line
			(start 0.12065 -0.2794)
			(end 0.12065 -0.3048)
			(stroke
				(width 0.1)
				(type default)
			)
			(layer "F.Fab")
		)
		(fp_line
			(start -0.12065 -0.2794)
			(end 0.12065 -0.2794)
			(stroke
				(width 0.1)
				(type default)
			)
			(layer "F.Fab")
		)
		(fp_line
			(start 0.120396 0.2794)
			(end -0.12065 0.2794)
			(stroke
				(width 0.1)
				(type default)
			)
			(layer "F.Fab")
		)
		(fp_line
			(start -0.12065 0.2794)
			(end -0.12065 0.3048)
			(stroke
				(width 0.1)
				(type default)
			)
			(layer "F.Fab")
		)
		(fp_line
			(start 0.67945 0.3048)
			(end 0.120396 0.3048)
			(stroke
				(width 0.1)
				(type default)
			)
			(layer "F.Fab")
		)
		(fp_line
			(start 0.120396 0.3048)
			(end 0.120396 0.2794)
			(stroke
				(width 0.1)
				(type default)
			)
			(layer "F.Fab")
		)
		(fp_line
			(start -0.12065 0.3048)
			(end -0.67945 0.3048)
			(stroke
				(width 0.1)
				(type default)
			)
			(layer "F.Fab")
		)
		(fp_line
			(start -0.67945 0.3048)
			(end -0.67945 -0.305054)
			(stroke
				(width 0.1)
				(type default)
			)
			(layer "F.Fab")
		)
		(pad "1" smd circle
			(at -0.40005 0 90)
			(size 0 0)
			(layers "F.Cu" "F.Mask" "F.Paste")
			(net "BMC_CPLD_GPIO_2_R1")
		)
		(pad "2" smd circle
			(at 0.40005 0 90)
			(size 0 0)
			(layers "F.Cu" "F.Mask" "F.Paste")
			(net "BMC_CPLD_GPIO_2")
		)
	)
	(footprint ""
		(layer "F.Cu")
		(at 18.034 -102.743 90)
		(property "Reference" "R114"
			(at 0 0 90)
			(layer "F.SilkS")
			(hide yes)
			(effects
				(font
					(size 1.27 1.27)
				)
			)
		)
		(property "Value" ""
			(at 0 0 90)
			(layer "F.Fab")
			(effects
				(font
					(size 1.27 1.27)
				)
			)
		)
		(duplicate_pad_numbers_are_jumpers no)
		(fp_line
			(start 0.7874 -0.4064)
			(end 0.7874 0.4064)
			(stroke
				(width 0.1524)
				(type default)
			)
			(layer "F.SilkS")
		)
		(fp_line
			(start -0.7874 -0.4064)
			(end 0.7874 -0.4064)
			(stroke
				(width 0.1524)
				(type default)
			)
			(layer "F.SilkS")
		)
		(fp_line
			(start 0.7874 0.4064)
			(end -0.7874 0.4064)
			(stroke
				(width 0.1524)
				(type default)
			)
			(layer "F.SilkS")
		)
		(fp_line
			(start -0.7874 0.4064)
			(end -0.7874 -0.4064)
			(stroke
				(width 0.1524)
				(type default)
			)
			(layer "F.SilkS")
		)
		(fp_line
			(start -0.12065 -0.305054)
			(end -0.12065 -0.2794)
			(stroke
				(width 0.1)
				(type default)
			)
			(layer "F.Fab")
		)
		(fp_line
			(start -0.67945 -0.305054)
			(end -0.12065 -0.305054)
			(stroke
				(width 0.1)
				(type default)
			)
			(layer "F.Fab")
		)
		(fp_line
			(start 0.67945 -0.3048)
			(end 0.67945 0.3048)
			(stroke
				(width 0.1)
				(type default)
			)
			(layer "F.Fab")
		)
		(fp_line
			(start 0.12065 -0.3048)
			(end 0.67945 -0.3048)
			(stroke
				(width 0.1)
				(type default)
			)
			(layer "F.Fab")
		)
		(fp_line
			(start 0.12065 -0.2794)
			(end 0.12065 -0.3048)
			(stroke
				(width 0.1)
				(type default)
			)
			(layer "F.Fab")
		)
		(fp_line
			(start -0.12065 -0.2794)
			(end 0.12065 -0.2794)
			(stroke
				(width 0.1)
				(type default)
			)
			(layer "F.Fab")
		)
		(fp_line
			(start 0.120396 0.2794)
			(end -0.12065 0.2794)
			(stroke
				(width 0.1)
				(type default)
			)
			(layer "F.Fab")
		)
		(fp_line
			(start -0.12065 0.2794)
			(end -0.12065 0.3048)
			(stroke
				(width 0.1)
				(type default)
			)
			(layer "F.Fab")
		)
		(fp_line
			(start 0.67945 0.3048)
			(end 0.120396 0.3048)
			(stroke
				(width 0.1)
				(type default)
			)
			(layer "F.Fab")
		)
		(fp_line
			(start 0.120396 0.3048)
			(end 0.120396 0.2794)
			(stroke
				(width 0.1)
				(type default)
			)
			(layer "F.Fab")
		)
		(fp_line
			(start -0.12065 0.3048)
			(end -0.67945 0.3048)
			(stroke
				(width 0.1)
				(type default)
			)
			(layer "F.Fab")
		)
		(fp_line
			(start -0.67945 0.3048)
			(end -0.67945 -0.305054)
			(stroke
				(width 0.1)
				(type default)
			)
			(layer "F.Fab")
		)
		(pad "1" smd circle
			(at -0.40005 0 90)
			(size 0 0)
			(layers "F.Cu" "F.Mask" "F.Paste")
			(net "SMB_BMC_MM16_R4_SDA")
		)
		(pad "2" smd circle
			(at 0.40005 0 90)
			(size 0 0)
			(layers "F.Cu" "F.Mask" "F.Paste")
			(net "SMB_BMC_MM16_R5_SDA")
		)
	)
	(footprint ""
		(layer "F.Cu")
		(at 26.924 -20.32)
		(property "Reference" "R32"
			(at 0 0 0)
			(layer "F.SilkS")
			(hide yes)
			(effects
				(font
					(size 1.27 1.27)
				)
			)
		)
		(property "Value" ""
			(at 0 0 0)
			(layer "F.Fab")
			(effects
				(font
					(size 1.27 1.27)
				)
			)
		)
		(duplicate_pad_numbers_are_jumpers no)
		(fp_line
			(start -0.7874 -0.4064)
			(end 0.7874 -0.4064)
			(stroke
				(width 0.1524)
				(type default)
			)
			(layer "F.SilkS")
		)
		(fp_line
			(start -0.7874 0.4064)
			(end -0.7874 -0.4064)
			(stroke
				(width 0.1524)
				(type default)
			)
			(layer "F.SilkS")
		)
		(fp_line
			(start 0.7874 -0.4064)
			(end 0.7874 0.4064)
			(stroke
				(width 0.1524)
				(type default)
			)
			(layer "F.SilkS")
		)
		(fp_line
			(start 0.7874 0.4064)
			(end -0.7874 0.4064)
			(stroke
				(width 0.1524)
				(type default)
			)
			(layer "F.SilkS")
		)
		(fp_line
			(start -0.67945 -0.305054)
			(end -0.12065 -0.305054)
			(stroke
				(width 0.1)
				(type default)
			)
			(layer "F.Fab")
		)
		(fp_line
			(start -0.67945 0.3048)
			(end -0.67945 -0.305054)
			(stroke
				(width 0.1)
				(type default)
			)
			(layer "F.Fab")
		)
		(fp_line
			(start -0.12065 -0.305054)
			(end -0.12065 -0.2794)
			(stroke
				(width 0.1)
				(type default)
			)
			(layer "F.Fab")
		)
		(fp_line
			(start -0.12065 -0.2794)
			(end 0.12065 -0.2794)
			(stroke
				(width 0.1)
				(type default)
			)
			(layer "F.Fab")
		)
		(fp_line
			(start -0.12065 0.2794)
			(end -0.12065 0.3048)
			(stroke
				(width 0.1)
				(type default)
			)
			(layer "F.Fab")
		)
		(fp_line
			(start -0.12065 0.3048)
			(end -0.67945 0.3048)
			(stroke
				(width 0.1)
				(type default)
			)
			(layer "F.Fab")
		)
		(fp_line
			(start 0.120396 0.2794)
			(end -0.12065 0.2794)
			(stroke
				(width 0.1)
				(type default)
			)
			(layer "F.Fab")
		)
		(fp_line
			(start 0.120396 0.3048)
			(end 0.120396 0.2794)
			(stroke
				(width 0.1)
				(type default)
			)
			(layer "F.Fab")
		)
		(fp_line
			(start 0.12065 -0.3048)
			(end 0.67945 -0.3048)
			(stroke
				(width 0.1)
				(type default)
			)
			(layer "F.Fab")
		)
		(fp_line
			(start 0.12065 -0.2794)
			(end 0.12065 -0.3048)
			(stroke
				(width 0.1)
				(type default)
			)
			(layer "F.Fab")
		)
		(fp_line
			(start 0.67945 -0.3048)
			(end 0.67945 0.3048)
			(stroke
				(width 0.1)
				(type default)
			)
			(layer "F.Fab")
		)
		(fp_line
			(start 0.67945 0.3048)
			(end 0.120396 0.3048)
			(stroke
				(width 0.1)
				(type default)
			)
			(layer "F.Fab")
		)
		(pad "1" smd circle
			(at -0.40005 0)
			(size 0 0)
			(layers "F.Cu" "F.Mask" "F.Paste")
			(net "P3V3_RGM")
		)
		(pad "2" smd circle
			(at 0.40005 0)
			(size 0 0)
			(layers "F.Cu" "F.Mask" "F.Paste")
			(net "V_BMC_DDC_SCL")
		)
	)
)
